(kicad_pcb
	(version 20260206)
	(generator "pcbnew")
	(generator_version "10.0")
	(general
		(thickness 1.6)
		(legacy_teardrops no)
	)
	(paper "A4")
	(title_block
		(title "04192023_DAF0TMB3IC0_F0TG_MB_C_brd_V02_OCP.brd")
		(comment 1 "Grand Teton / footprints 5015-5021 of 8354")
	)
	(layers
		(0 "F.Cu" signal "TOP")
		(4 "In1.Cu" signal "GND")
		(6 "In2.Cu" signal "IN1")
		(8 "In3.Cu" signal "GND1")
		(10 "In4.Cu" signal "IN2")
		(12 "In5.Cu" signal "GND2")
		(14 "In6.Cu" signal "IN3")
		(16 "In7.Cu" signal "GND3")
		(18 "In8.Cu" signal "VCC")
		(20 "In9.Cu" signal "VCC1")
		(22 "In10.Cu" signal "GND4")
		(24 "In11.Cu" signal "IN4")
		(26 "In12.Cu" signal "GND5")
		(28 "In13.Cu" signal "IN5")
		(30 "In14.Cu" signal "GND6")
		(32 "In15.Cu" signal "IN6")
		(34 "In16.Cu" signal "GND7")
		(2 "B.Cu" signal "BOTTOM")
		(9 "F.Adhes" user "F.Adhesive")
		(11 "B.Adhes" user "B.Adhesive")
		(13 "F.Paste" user "Package Geometry/Pastemask Top")
		(15 "B.Paste" user "Package Geometry/Pastemask Bottom")
		(5 "F.SilkS" user "Ref Des/Silkscreen Top")
		(7 "B.SilkS" user "Ref Des/Silkscreen Bottom")
		(1 "F.Mask" user "Board Geometry/Soldermask Top")
		(3 "B.Mask" user "Board Geometry/Soldermask Bottom")
		(17 "Dwgs.User" user "User.Drawings")
		(19 "Cmts.User" user "User.Comments")
		(21 "Eco1.User" user "User.Eco1")
		(23 "Eco2.User" user "User.Eco2")
		(25 "Edge.Cuts" user "Board Geometry/Outline")
		(27 "Margin" user)
		(31 "F.CrtYd" user "Package Geometry/Place Bound Top")
		(29 "B.CrtYd" user "Package Geometry/Place Bound Bottom")
		(35 "F.Fab" user "Ref Des/Assembly Top")
		(33 "B.Fab" user "Ref Des/Assembly Bottom")
	)
	(footprint ""
		(layer "B.Cu")
		(at 385.06781 -389.49503)
		(property "Reference" "C7018"
			(at 2.82956 3.177032 0)
			(unlocked yes)
			(layer "B.SilkS")
			(effects
				(font
					(size 0.7874 0.5842)
					(thickness 0.1524)
				)
				(justify left mirror)
			)
		)
		(property "Value" ""
			(at 0 0 0)
			(layer "B.Fab")
			(effects
				(font
					(size 1.27 1.27)
				)
				(justify mirror)
			)
		)
		(duplicate_pad_numbers_are_jumpers no)
		(fp_line
			(start -4.53898 -2.15011)
			(end -4.53898 2.15011)
			(stroke
				(width 0.1524)
				(type default)
			)
			(layer "B.SilkS")
		)
		(fp_line
			(start -4.53898 2.15011)
			(end 4.53898 2.15011)
			(stroke
				(width 0.1524)
				(type default)
			)
			(layer "B.SilkS")
		)
		(fp_line
			(start 4.53898 -2.150618)
			(end 4.539742 2.152142)
			(stroke
				(width 0.1524)
				(type default)
			)
			(layer "B.SilkS")
		)
		(fp_line
			(start 4.53898 -2.15011)
			(end -4.53898 -2.15011)
			(stroke
				(width 0.1524)
				(type default)
			)
			(layer "B.SilkS")
		)
		(fp_line
			(start 4.53898 2.15011)
			(end 4.53898 -2.15011)
			(stroke
				(width 0.1524)
				(type default)
			)
			(layer "B.SilkS")
		)
		(fp_line
			(start 4.69138 -2.150618)
			(end 4.692396 2.161032)
			(stroke
				(width 0.1524)
				(type default)
			)
			(layer "B.SilkS")
		)
		(fp_line
			(start 4.83108 2.150364)
			(end 4.447794 2.149348)
			(stroke
				(width 0.1524)
				(type default)
			)
			(layer "B.SilkS")
		)
		(fp_line
			(start 4.84378 -2.150618)
			(end 4.53898 -2.150618)
			(stroke
				(width 0.1524)
				(type default)
			)
			(layer "B.SilkS")
		)
		(fp_line
			(start 4.84378 -2.150618)
			(end 4.842256 2.163064)
			(stroke
				(width 0.1524)
				(type default)
			)
			(layer "B.SilkS")
		)
		(fp_line
			(start -3.64998 -2.15011)
			(end -3.64998 2.15011)
			(stroke
				(width 0.1)
				(type default)
			)
			(layer "B.Fab")
		)
		(fp_line
			(start -3.64998 2.15011)
			(end 3.64998 2.15011)
			(stroke
				(width 0.1)
				(type default)
			)
			(layer "B.Fab")
		)
		(fp_line
			(start 3.64998 -2.15011)
			(end -3.64998 -2.15011)
			(stroke
				(width 0.1)
				(type default)
			)
			(layer "B.Fab")
		)
		(fp_line
			(start 3.64998 2.15011)
			(end 3.64998 -2.15011)
			(stroke
				(width 0.1)
				(type default)
			)
			(layer "B.Fab")
		)
		(fp_text user "-"
			(at -3.017774 2.359152 0)
			(unlocked yes)
			(layer "B.SilkS")
			(effects
				(font
					(size 1.905 1.4224)
					(thickness 0.1524)
				)
				(justify left mirror)
			)
		)
		(fp_text user "+"
			(at 6.214872 -0.337058 0)
			(unlocked yes)
			(layer "B.SilkS")
			(effects
				(font
					(size 1.905 1.4224)
					(thickness 0.1524)
				)
				(justify left mirror)
			)
		)
		(fp_text user "-"
			(at -4.313174 -0.094488 0)
			(unlocked yes)
			(layer "B.Fab")
			(effects
				(font
					(size 1.905 1.4224)
					(thickness 0.1524)
				)
				(justify left mirror)
			)
		)
		(fp_text user "+"
			(at 6.214872 -0.337058 0)
			(unlocked yes)
			(layer "B.Fab")
			(effects
				(font
					(size 1.905 1.4224)
					(thickness 0.1524)
				)
				(justify left mirror)
			)
		)
		(pad "1" smd rect
			(at 3.199892 0 180)
			(size 2.413 2.8194)
			(layers "B.Cu" "B.Mask" "B.Paste")
			(net "P0V9_CPU0_RT3_2A")
		)
		(pad "2" smd rect
			(at -3.199892 0 180)
			(size 2.413 2.8194)
			(layers "B.Cu" "B.Mask" "B.Paste")
			(net "GND")
		)
	)
	(footprint ""
		(layer "B.Cu")
		(at 94.470474 -302.805592)
		(property "Reference" "R544"
			(at 0 0 0)
			(layer "B.SilkS")
			(hide yes)
			(effects
				(font
					(size 1.27 1.27)
				)
				(justify mirror)
			)
		)
		(property "Value" ""
			(at 0 0 0)
			(layer "B.Fab")
			(effects
				(font
					(size 1.27 1.27)
				)
				(justify mirror)
			)
		)
		(duplicate_pad_numbers_are_jumpers no)
		(fp_line
			(start -0.7874 -0.4064)
			(end -0.7874 0.4064)
			(stroke
				(width 0.1524)
				(type default)
			)
			(layer "B.SilkS")
		)
		(fp_line
			(start -0.7874 0.4064)
			(end 0.7874 0.4064)
			(stroke
				(width 0.1524)
				(type default)
			)
			(layer "B.SilkS")
		)
		(fp_line
			(start 0.7874 -0.4064)
			(end -0.7874 -0.4064)
			(stroke
				(width 0.1524)
				(type default)
			)
			(layer "B.SilkS")
		)
		(fp_line
			(start 0.7874 0.4064)
			(end 0.7874 -0.4064)
			(stroke
				(width 0.1524)
				(type default)
			)
			(layer "B.SilkS")
		)
		(fp_line
			(start -0.67945 -0.3048)
			(end -0.67945 0.3048)
			(stroke
				(width 0.1)
				(type default)
			)
			(layer "B.Fab")
		)
		(fp_line
			(start -0.67945 0.3048)
			(end -0.120396 0.3048)
			(stroke
				(width 0.1)
				(type default)
			)
			(layer "B.Fab")
		)
		(fp_line
			(start -0.12065 -0.3048)
			(end -0.67945 -0.3048)
			(stroke
				(width 0.1)
				(type default)
			)
			(layer "B.Fab")
		)
		(fp_line
			(start -0.12065 -0.2794)
			(end -0.12065 -0.3048)
			(stroke
				(width 0.1)
				(type default)
			)
			(layer "B.Fab")
		)
		(fp_line
			(start -0.120396 0.2794)
			(end 0.12065 0.2794)
			(stroke
				(width 0.1)
				(type default)
			)
			(layer "B.Fab")
		)
		(fp_line
			(start -0.120396 0.3048)
			(end -0.120396 0.2794)
			(stroke
				(width 0.1)
				(type default)
			)
			(layer "B.Fab")
		)
		(fp_line
			(start 0.12065 -0.305054)
			(end 0.12065 -0.2794)
			(stroke
				(width 0.1)
				(type default)
			)
			(layer "B.Fab")
		)
		(fp_line
			(start 0.12065 -0.2794)
			(end -0.12065 -0.2794)
			(stroke
				(width 0.1)
				(type default)
			)
			(layer "B.Fab")
		)
		(fp_line
			(start 0.12065 0.2794)
			(end 0.12065 0.3048)
			(stroke
				(width 0.1)
				(type default)
			)
			(layer "B.Fab")
		)
		(fp_line
			(start 0.12065 0.3048)
			(end 0.67945 0.3048)
			(stroke
				(width 0.1)
				(type default)
			)
			(layer "B.Fab")
		)
		(fp_line
			(start 0.67945 -0.305054)
			(end 0.12065 -0.305054)
			(stroke
				(width 0.1)
				(type default)
			)
			(layer "B.Fab")
		)
		(fp_line
			(start 0.67945 0.3048)
			(end 0.67945 -0.305054)
			(stroke
				(width 0.1)
				(type default)
			)
			(layer "B.Fab")
		)
		(pad "1" smd circle
			(at 0.40005 0 180)
			(size 0 0)
			(layers "B.Cu" "B.Mask" "B.Paste")
			(net "IRQ_CPU_BMC_NMI_N")
		)
		(pad "2" smd circle
			(at -0.40005 0 180)
			(size 0 0)
			(layers "B.Cu" "B.Mask" "B.Paste")
			(net "PVDD18_S5_P1")
		)
	)
	(footprint ""
		(layer "B.Cu")
		(at 401.190968 -390.035034)
		(property "Reference" "C7016"
			(at 0 0 0)
			(layer "B.SilkS")
			(hide yes)
			(effects
				(font
					(size 1.27 1.27)
				)
				(justify mirror)
			)
		)
		(property "Value" ""
			(at 0 0 0)
			(layer "B.Fab")
			(effects
				(font
					(size 1.27 1.27)
				)
				(justify mirror)
			)
		)
		(duplicate_pad_numbers_are_jumpers no)
		(fp_line
			(start -1.524 -0.762)
			(end -1.524 0.762)
			(stroke
				(width 0.1524)
				(type default)
			)
			(layer "B.SilkS")
		)
		(fp_line
			(start -1.524 0.762)
			(end 1.524 0.762)
			(stroke
				(width 0.1524)
				(type default)
			)
			(layer "B.SilkS")
		)
		(fp_line
			(start 1.524 -0.762)
			(end -1.524 -0.762)
			(stroke
				(width 0.1524)
				(type default)
			)
			(layer "B.SilkS")
		)
		(fp_line
			(start 1.524 0.762)
			(end 1.524 -0.762)
			(stroke
				(width 0.1524)
				(type default)
			)
			(layer "B.SilkS")
		)
		(fp_line
			(start -1.1049 -0.724916)
			(end 1.1049 -0.724916)
			(stroke
				(width 0.1)
				(type default)
			)
			(layer "B.Fab")
		)
		(fp_line
			(start -1.1049 0.724916)
			(end -1.1049 -0.724916)
			(stroke
				(width 0.1)
				(type default)
			)
			(layer "B.Fab")
		)
		(fp_line
			(start 1.1049 -0.724916)
			(end 1.1049 0.724916)
			(stroke
				(width 0.1)
				(type default)
			)
			(layer "B.Fab")
		)
		(fp_line
			(start 1.1049 0.724916)
			(end -1.1049 0.724916)
			(stroke
				(width 0.1)
				(type default)
			)
			(layer "B.Fab")
		)
		(pad "1" smd rect
			(at 0.889 0)
			(size 1.016 1.27)
			(layers "B.Cu" "B.Mask" "B.Paste")
			(net "P0V9_CPU0_RT2_2A")
		)
		(pad "2" smd rect
			(at -0.889 0)
			(size 1.016 1.27)
			(layers "B.Cu" "B.Mask" "B.Paste")
			(net "GND")
		)
	)
	(footprint ""
		(layer "B.Cu")
		(at 268.892528 -193.99631)
		(property "Reference" "C108"
			(at 0 0 0)
			(layer "B.SilkS")
			(hide yes)
			(effects
				(font
					(size 1.27 1.27)
				)
				(justify mirror)
			)
		)
		(property "Value" ""
			(at 0 0 0)
			(layer "B.Fab")
			(effects
				(font
					(size 1.27 1.27)
				)
				(justify mirror)
			)
		)
		(duplicate_pad_numbers_are_jumpers no)
		(fp_line
			(start -0.7874 -0.4064)
			(end -0.7874 0.4064)
			(stroke
				(width 0.1524)
				(type default)
			)
			(layer "B.SilkS")
		)
		(fp_line
			(start -0.7874 0.4064)
			(end 0.7874 0.4064)
			(stroke
				(width 0.1524)
				(type default)
			)
			(layer "B.SilkS")
		)
		(fp_line
			(start 0.7874 -0.4064)
			(end -0.7874 -0.4064)
			(stroke
				(width 0.1524)
				(type default)
			)
			(layer "B.SilkS")
		)
		(fp_line
			(start 0.7874 0.4064)
			(end 0.7874 -0.4064)
			(stroke
				(width 0.1524)
				(type default)
			)
			(layer "B.SilkS")
		)
		(fp_line
			(start -0.67945 -0.3048)
			(end -0.67945 0.3048)
			(stroke
				(width 0.1)
				(type default)
			)
			(layer "B.Fab")
		)
		(fp_line
			(start -0.67945 0.3048)
			(end -0.120396 0.3048)
			(stroke
				(width 0.1)
				(type default)
			)
			(layer "B.Fab")
		)
		(fp_line
			(start -0.12065 -0.3048)
			(end -0.67945 -0.3048)
			(stroke
				(width 0.1)
				(type default)
			)
			(layer "B.Fab")
		)
		(fp_line
			(start -0.12065 -0.2794)
			(end -0.12065 -0.3048)
			(stroke
				(width 0.1)
				(type default)
			)
			(layer "B.Fab")
		)
		(fp_line
			(start -0.120396 0.2794)
			(end 0.12065 0.2794)
			(stroke
				(width 0.1)
				(type default)
			)
			(layer "B.Fab")
		)
		(fp_line
			(start -0.120396 0.3048)
			(end -0.120396 0.2794)
			(stroke
				(width 0.1)
				(type default)
			)
			(layer "B.Fab")
		)
		(fp_line
			(start 0.12065 -0.305054)
			(end 0.12065 -0.2794)
			(stroke
				(width 0.1)
				(type default)
			)
			(layer "B.Fab")
		)
		(fp_line
			(start 0.12065 -0.2794)
			(end -0.12065 -0.2794)
			(stroke
				(width 0.1)
				(type default)
			)
			(layer "B.Fab")
		)
		(fp_line
			(start 0.12065 0.2794)
			(end 0.12065 0.3048)
			(stroke
				(width 0.1)
				(type default)
			)
			(layer "B.Fab")
		)
		(fp_line
			(start 0.12065 0.3048)
			(end 0.67945 0.3048)
			(stroke
				(width 0.1)
				(type default)
			)
			(layer "B.Fab")
		)
		(fp_line
			(start 0.67945 -0.305054)
			(end 0.12065 -0.305054)
			(stroke
				(width 0.1)
				(type default)
			)
			(layer "B.Fab")
		)
		(fp_line
			(start 0.67945 0.3048)
			(end 0.67945 -0.305054)
			(stroke
				(width 0.1)
				(type default)
			)
			(layer "B.Fab")
		)
		(pad "1" smd circle
			(at 0.40005 0 180)
			(size 0 0)
			(layers "B.Cu" "B.Mask" "B.Paste")
			(net "P3V3_AUX")
		)
		(pad "2" smd circle
			(at -0.40005 0 180)
			(size 0 0)
			(layers "B.Cu" "B.Mask" "B.Paste")
			(net "GND")
		)
	)
	(footprint ""
		(layer "B.Cu")
		(at 358.58069 -391.2616 180)
		(property "Reference" "R1042"
			(at 0 0 0)
			(layer "B.SilkS")
			(hide yes)
			(effects
				(font
					(size 1.27 1.27)
				)
				(justify mirror)
			)
		)
		(property "Value" ""
			(at 0 0 0)
			(layer "B.Fab")
			(effects
				(font
					(size 1.27 1.27)
				)
				(justify mirror)
			)
		)
		(duplicate_pad_numbers_are_jumpers no)
		(fp_line
			(start 0.32512 0.175006)
			(end 0.32512 -0.175006)
			(stroke
				(width 0.1)
				(type default)
			)
			(layer "B.Fab")
		)
		(fp_line
			(start 0.32512 -0.175006)
			(end -0.32512 -0.175006)
			(stroke
				(width 0.1)
				(type default)
			)
			(layer "B.Fab")
		)
		(fp_line
			(start -0.32512 0.175006)
			(end 0.32512 0.175006)
			(stroke
				(width 0.1)
				(type default)
			)
			(layer "B.Fab")
		)
		(fp_line
			(start -0.32512 -0.175006)
			(end -0.32512 0.175006)
			(stroke
				(width 0.1)
				(type default)
			)
			(layer "B.Fab")
		)
		(pad "1" smd rect
			(at 0.2667 0)
			(size 0.3048 0.381)
			(layers "B.Cu" "B.Mask" "B.Paste")
			(net "NCF_CPU0_P1_GND")
		)
		(pad "2" smd rect
			(at -0.2667 0 180)
			(size 0.3048 0.381)
			(layers "B.Cu" "B.Mask" "B.Paste")
			(net "GND")
		)
	)
	(footprint ""
		(layer "B.Cu")
		(at 400.211798 -326.666352)
		(property "Reference" "R742"
			(at 0 0 0)
			(layer "B.SilkS")
			(hide yes)
			(effects
				(font
					(size 1.27 1.27)
				)
				(justify mirror)
			)
		)
		(property "Value" ""
			(at 0 0 0)
			(layer "B.Fab")
			(effects
				(font
					(size 1.27 1.27)
				)
				(justify mirror)
			)
		)
		(duplicate_pad_numbers_are_jumpers no)
		(fp_line
			(start -0.7874 -0.4064)
			(end -0.7874 0.4064)
			(stroke
				(width 0.1524)
				(type default)
			)
			(layer "B.SilkS")
		)
		(fp_line
			(start -0.7874 0.4064)
			(end 0.7874 0.4064)
			(stroke
				(width 0.1524)
				(type default)
			)
			(layer "B.SilkS")
		)
		(fp_line
			(start 0.7874 -0.4064)
			(end -0.7874 -0.4064)
			(stroke
				(width 0.1524)
				(type default)
			)
			(layer "B.SilkS")
		)
		(fp_line
			(start 0.7874 0.4064)
			(end 0.7874 -0.4064)
			(stroke
				(width 0.1524)
				(type default)
			)
			(layer "B.SilkS")
		)
		(fp_line
			(start -0.67945 -0.3048)
			(end -0.67945 0.3048)
			(stroke
				(width 0.1)
				(type default)
			)
			(layer "B.Fab")
		)
		(fp_line
			(start -0.67945 0.3048)
			(end -0.120396 0.3048)
			(stroke
				(width 0.1)
				(type default)
			)
			(layer "B.Fab")
		)
		(fp_line
			(start -0.12065 -0.3048)
			(end -0.67945 -0.3048)
			(stroke
				(width 0.1)
				(type default)
			)
			(layer "B.Fab")
		)
		(fp_line
			(start -0.12065 -0.2794)
			(end -0.12065 -0.3048)
			(stroke
				(width 0.1)
				(type default)
			)
			(layer "B.Fab")
		)
		(fp_line
			(start -0.120396 0.2794)
			(end 0.12065 0.2794)
			(stroke
				(width 0.1)
				(type default)
			)
			(layer "B.Fab")
		)
		(fp_line
			(start -0.120396 0.3048)
			(end -0.120396 0.2794)
			(stroke
				(width 0.1)
				(type default)
			)
			(layer "B.Fab")
		)
		(fp_line
			(start 0.12065 -0.305054)
			(end 0.12065 -0.2794)
			(stroke
				(width 0.1)
				(type default)
			)
			(layer "B.Fab")
		)
		(fp_line
			(start 0.12065 -0.2794)
			(end -0.12065 -0.2794)
			(stroke
				(width 0.1)
				(type default)
			)
			(layer "B.Fab")
		)
		(fp_line
			(start 0.12065 0.2794)
			(end 0.12065 0.3048)
			(stroke
				(width 0.1)
				(type default)
			)
			(layer "B.Fab")
		)
		(fp_line
			(start 0.12065 0.3048)
			(end 0.67945 0.3048)
			(stroke
				(width 0.1)
				(type default)
			)
			(layer "B.Fab")
		)
		(fp_line
			(start 0.67945 -0.305054)
			(end 0.12065 -0.305054)
			(stroke
				(width 0.1)
				(type default)
			)
			(layer "B.Fab")
		)
		(fp_line
			(start 0.67945 0.3048)
			(end 0.67945 -0.305054)
			(stroke
				(width 0.1)
				(type default)
			)
			(layer "B.Fab")
		)
		(pad "1" smd circle
			(at 0.40005 0 180)
			(size 0 0)
			(layers "B.Cu" "B.Mask" "B.Paste")
			(net "PVDD18_S5_P0")
		)
		(pad "2" smd circle
			(at -0.40005 0 180)
			(size 0 0)
			(layers "B.Cu" "B.Mask" "B.Paste")
			(net "PD_ESPI_CPU0_CLK2")
		)
	)
	(footprint ""
		(layer "B.Cu")
		(at 356.29596 -258.795012 180)
		(property "Reference" "C2598"
			(at 0 0 0)
			(layer "B.SilkS")
			(hide yes)
			(effects
				(font
					(size 1.27 1.27)
				)
				(justify mirror)
			)
		)
		(property "Value" ""
			(at 0 0 0)
			(layer "B.Fab")
			(effects
				(font
					(size 1.27 1.27)
				)
				(justify mirror)
			)
		)
		(duplicate_pad_numbers_are_jumpers no)
		(fp_line
			(start 0.7874 0.4064)
			(end 0.7874 -0.4064)
			(stroke
				(width 0.1524)
				(type default)
			)
			(layer "B.SilkS")
		)
		(fp_line
			(start 0.7874 -0.4064)
			(end -0.7874 -0.4064)
			(stroke
				(width 0.1524)
				(type default)
			)
			(layer "B.SilkS")
		)
		(fp_line
			(start -0.7874 0.4064)
			(end 0.7874 0.4064)
			(stroke
				(width 0.1524)
				(type default)
			)
			(layer "B.SilkS")
		)
		(fp_line
			(start -0.7874 -0.4064)
			(end -0.7874 0.4064)
			(stroke
				(width 0.1524)
				(type default)
			)
			(layer "B.SilkS")
		)
		(fp_line
			(start 0.67945 0.3048)
			(end 0.67945 -0.305054)
			(stroke
				(width 0.1)
				(type default)
			)
			(layer "B.Fab")
		)
		(fp_line
			(start 0.67945 -0.305054)
			(end 0.12065 -0.305054)
			(stroke
				(width 0.1)
				(type default)
			)
			(layer "B.Fab")
		)
		(fp_line
			(start 0.12065 0.3048)
			(end 0.67945 0.3048)
			(stroke
				(width 0.1)
				(type default)
			)
			(layer "B.Fab")
		)
		(fp_line
			(start 0.12065 0.2794)
			(end 0.12065 0.3048)
			(stroke
				(width 0.1)
				(type default)
			)
			(layer "B.Fab")
		)
		(fp_line
			(start 0.12065 -0.2794)
			(end -0.12065 -0.2794)
			(stroke
				(width 0.1)
				(type default)
			)
			(layer "B.Fab")
		)
		(fp_line
			(start 0.12065 -0.305054)
			(end 0.12065 -0.2794)
			(stroke
				(width 0.1)
				(type default)
			)
			(layer "B.Fab")
		)
		(fp_line
			(start -0.120396 0.3048)
			(end -0.120396 0.2794)
			(stroke
				(width 0.1)
				(type default)
			)
			(layer "B.Fab")
		)
		(fp_line
			(start -0.120396 0.2794)
			(end 0.12065 0.2794)
			(stroke
				(width 0.1)
				(type default)
			)
			(layer "B.Fab")
		)
		(fp_line
			(start -0.12065 -0.2794)
			(end -0.12065 -0.3048)
			(stroke
				(width 0.1)
				(type default)
			)
			(layer "B.Fab")
		)
		(fp_line
			(start -0.12065 -0.3048)
			(end -0.67945 -0.3048)
			(stroke
				(width 0.1)
				(type default)
			)
			(layer "B.Fab")
		)
		(fp_line
			(start -0.67945 0.3048)
			(end -0.120396 0.3048)
			(stroke
				(width 0.1)
				(type default)
			)
			(layer "B.Fab")
		)
		(fp_line
			(start -0.67945 -0.3048)
			(end -0.67945 0.3048)
			(stroke
				(width 0.1)
				(type default)
			)
			(layer "B.Fab")
		)
		(pad "1" smd circle
			(at 0.40005 0)
			(size 0 0)
			(layers "B.Cu" "B.Mask" "B.Paste")
			(net "PVDDIO_P0")
		)
		(pad "2" smd circle
			(at -0.40005 0)
			(size 0 0)
			(layers "B.Cu" "B.Mask" "B.Paste")
			(net "GND")
		)
	)
)
